# TIMECARD (Time Appliance Project (Time Card)) — schematic netlist excerpt (pin names and nets, part order shuffled) for the footprints in the layout excerpt that follows; sources: Cadence DE-HDL packaged netlist, KiCad conversion of R4006-B0001-02_R01.brd

R56  RESISTOR  4.7KOHM 1%  pkg SMC_0402R_H016  page 9 : \1\ = XP3R3V ; \2\ = PCIE_CONN_PERST_N

(kicad_pcb
	(version 20260206)
	(generator "pcbnew")
	(generator_version "10.0")
	(general
		(thickness 1.6)
		(legacy_teardrops no)
	)
	(paper "A4")
	(title_block
		(title "timecard-production-celestica-r4006 — R4006-B0001-02_R01.brd")
		(comment 1 "Time Appliance Project (Time Card) / footprints 442-442 of 1113")
	)
	(layers
		(0 "F.Cu" signal "TOP")
		(4 "In1.Cu" signal "L02_GND1")
		(6 "In2.Cu" signal "L03_SIG1")
		(8 "In3.Cu" signal "L04_GND2")
		(10 "In4.Cu" signal "L05_VCC1")
		(12 "In5.Cu" signal "L06_VCC2")
		(14 "In6.Cu" signal "L07_GND3")
		(16 "In7.Cu" signal "L08_SIG2")
		(18 "In8.Cu" signal "L09_GND4")
		(2 "B.Cu" signal "BOTTOM")
		(9 "F.Adhes" user "F.Adhesive")
		(11 "B.Adhes" user "B.Adhesive")
		(13 "F.Paste" user "Package Geometry/Pastemask Top")
		(15 "B.Paste" user "Package Geometry/Pastemask Bottom")
		(5 "F.SilkS" user "Ref Des/Silkscreen Top")
		(7 "B.SilkS" user "Ref Des/Silkscreen Bottom")
		(1 "F.Mask" user "Board Geometry/Soldermask Top")
		(3 "B.Mask" user "Board Geometry/Soldermask Bottom")
		(17 "Dwgs.User" user "User.Drawings")
		(19 "Cmts.User" user "User.Comments")
		(21 "Eco1.User" user "User.Eco1")
		(23 "Eco2.User" user "User.Eco2")
		(25 "Edge.Cuts" user "Board Geometry/Outline")
		(27 "Margin" user)
		(31 "F.CrtYd" user "Package Geometry/Place Bound Top")
		(29 "B.CrtYd" user "Package Geometry/Place Bound Bottom")
		(35 "F.Fab" user "Ref Des/Assembly Top")
		(33 "B.Fab" user "Ref Des/Assembly Bottom")
	)
	(footprint ""
		(layer "F.Cu")
		(at 66.4464 -15.367)
		(property "Reference" "R56"
			(at -0.0254 2.19837 0)
			(unlocked yes)
			(layer "F.SilkS")
			(effects
				(font
					(size 0.7874 0.5842)
					(thickness 0.1524)
				)
			)
		)
		(property "Value" "VAL*"
			(at 0.02032 2.13233 0)
			(unlocked yes)
			(layer "F.Fab")
			(hide yes)
			(effects
				(font
					(size 0.7874 0.5842)
					(thickness 0.1524)
				)
			)
		)
		(property "Tolerance" "TOL*"
			(at 0.044704 3.05435 0)
			(unlocked yes)
			(layer "Cmts.User")
			(hide yes)
			(effects
				(font
					(size 0.7874 0.5842)
					(thickness 0.1524)
				)
			)
		)
		(property "User Part Number" "PARTNUM*"
			(at 0.02032 4.024884 0)
			(unlocked yes)
			(layer "Cmts.User")
			(hide yes)
			(effects
				(font
					(size 0.7874 0.5842)
					(thickness 0.1524)
				)
			)
		)
		(property "Device Type" "RESISTOR-G155-14701-01,4.7KOHMA"
			(at 0.008382 1.210564 0)
			(unlocked yes)
			(layer "F.Fab")
			(hide yes)
			(effects
				(font
					(size 0.7874 0.5842)
					(thickness 0.1524)
				)
			)
		)
		(duplicate_pad_numbers_are_jumpers no)
		(fp_line
			(start -1.143 -0.5588)
			(end -1.143 0.5588)
			(stroke
				(width 0.1)
				(type default)
			)
			(layer "F.SilkS")
		)
		(fp_line
			(start -1.143 0.5588)
			(end 1.143 0.5588)
			(stroke
				(width 0.1)
				(type default)
			)
			(layer "F.SilkS")
		)
		(fp_line
			(start 1.143 -0.5588)
			(end -1.143 -0.5588)
			(stroke
				(width 0.1)
				(type default)
			)
			(layer "F.SilkS")
		)
		(fp_line
			(start 1.143 0.5588)
			(end 1.143 -0.5588)
			(stroke
				(width 0.1)
				(type default)
			)
			(layer "F.SilkS")
		)
		(fp_rect
			(start -1.143 0.5588)
			(end 1.143 -0.5588)
			(stroke
				(width 0)
				(type default)
			)
			(fill no)
			(layer "F.CrtYd")
		)
		(fp_line
			(start -0.508 -0.3048)
			(end -0.508 0.3048)
			(stroke
				(width 0.1)
				(type default)
			)
			(layer "F.Fab")
		)
		(fp_line
			(start -0.508 0.3048)
			(end 0.508 0.3048)
			(stroke
				(width 0.1)
				(type default)
			)
			(layer "F.Fab")
		)
		(fp_line
			(start 0.508 -0.3048)
			(end -0.508 -0.3048)
			(stroke
				(width 0.1)
				(type default)
			)
			(layer "F.Fab")
		)
		(fp_line
			(start 0.508 0.3048)
			(end 0.508 -0.3048)
			(stroke
				(width 0.1)
				(type default)
			)
			(layer "F.Fab")
		)
		(pad "1" smd rect
			(at -0.5334 0)
			(size 0.7112 0.6096)
			(layers "F.Cu" "F.Mask" "F.Paste")
			(net "XP3R3V")
		)
		(pad "2" smd rect
			(at 0.5334 0)
			(size 0.7112 0.6096)
			(layers "F.Cu" "F.Mask" "F.Paste")
			(net "PCIE_CONN_PERST_N")
		)
		(zone
			(layer "F.Cu")
			(hatch none 0.5)
			(connect_pads
				(clearance 0)
			)
			(min_thickness 0.25)
			(keepout
				(tracks allowed)
				(vias not_allowed)
				(pads allowed)
				(copperpour not_allowed)
				(footprints allowed)
			)
			(placement
				(enabled no)
				(sheetname "")
			)
			(fill
				(thermal_gap 0.5)
				(thermal_bridge_width 0.5)
				(island_removal_mode 0)
			)
			(polygon
				(pts
					(xy 66.3702 -15.0622) (xy 66.5226 -15.0622) (xy 66.5226 -15.6718) (xy 66.3702 -15.6718)
				)
			)
		)
	)
)
